(kicad_pcb
	(version 20260206)
	(generator "pcbnew")
	(generator_version "10.0")
	(general
		(thickness 1.6)
		(legacy_teardrops no)
	)
	(paper "A4")
	(title_block
		(title "Bryce Canyon_R.DPB_16317-1_OCP.brd")
		(comment 1 "Bryce Canyon / footprints 1262-1268 of 2099")
	)
	(layers
		(0 "F.Cu" signal "TOP")
		(4 "In1.Cu" signal "L2GND")
		(6 "In2.Cu" signal "L3")
		(8 "In3.Cu" signal "L4VCC")
		(10 "In4.Cu" signal "L5VCC")
		(12 "In5.Cu" signal "L6")
		(14 "In6.Cu" signal "L7GND")
		(2 "B.Cu" signal "BOTTOM")
		(9 "F.Adhes" user "F.Adhesive")
		(11 "B.Adhes" user "B.Adhesive")
		(13 "F.Paste" user "Package Geometry/Pastemask Top")
		(15 "B.Paste" user "Package Geometry/Pastemask Bottom")
		(5 "F.SilkS" user "Ref Des/Silkscreen Top")
		(7 "B.SilkS" user "Ref Des/Silkscreen Bottom")
		(1 "F.Mask" user "Board Geometry/Soldermask Top")
		(3 "B.Mask" user "Board Geometry/Soldermask Bottom")
		(17 "Dwgs.User" user "User.Drawings")
		(19 "Cmts.User" user "User.Comments")
		(21 "Eco1.User" user "User.Eco1")
		(23 "Eco2.User" user "User.Eco2")
		(25 "Edge.Cuts" user "Board Geometry/Outline")
		(27 "Margin" user)
		(31 "F.CrtYd" user "Package Geometry/Place Bound Top")
		(29 "B.CrtYd" user "Package Geometry/Place Bound Bottom")
		(35 "F.Fab" user "Ref Des/Assembly Top")
		(33 "B.Fab" user "Ref Des/Assembly Bottom")
	)
	(footprint ""
		(layer "F.Cu")
		(at 381.3302 -32.8676 180)
		(property "Reference" "R810"
			(at 0 0 180)
			(layer "F.SilkS")
			(hide yes)
			(effects
				(font
					(size 1.27 1.27)
				)
			)
		)
		(property "Value" "220R3F-1-GP"
			(at -0.0254 -2.5146 180)
			(unlocked yes)
			(layer "F.Fab")
			(hide yes)
			(effects
				(font
					(size 1.016 1.016)
					(thickness 0.1524)
				)
			)
		)
		(property "Device Type" "R603H22"
			(at -0.0254 -4.0386 180)
			(unlocked yes)
			(layer "F.Fab")
			(hide yes)
			(effects
				(font
					(size 1.016 1.016)
					(thickness 0.1524)
				)
			)
		)
		(duplicate_pad_numbers_are_jumpers no)
		(fp_line
			(start 0.2032 0)
			(end 0.4826 0)
			(stroke
				(width 0.2032)
				(type default)
			)
			(layer "F.SilkS")
		)
		(fp_line
			(start -0.4826 0)
			(end -0.2032 0)
			(stroke
				(width 0.2032)
				(type default)
			)
			(layer "F.SilkS")
		)
		(fp_rect
			(start -0.5842 1.3335)
			(end 0.5842 -1.3335)
			(stroke
				(width 0)
				(type default)
			)
			(fill no)
			(layer "F.CrtYd")
		)
		(fp_rect
			(start -0.5842 1.3335)
			(end 0.5842 -1.3335)
			(stroke
				(width 0)
				(type default)
			)
			(fill no)
			(layer "F.Fab")
		)
		(pad "1" smd custom
			(at 0 -0.762 180)
			(size 0.2159 0.2159)
			(layers "F.Cu" "F.Mask" "F.Paste")
			(net "HDD_PRSNT_32")
			(options
				(clearance outline)
				(anchor circle)
			)
			(primitives
				(gr_poly
					(pts
						(arc
							(start -0.3302 -0.4318)
							(mid -0.402042 -0.402042)
							(end -0.4318 -0.3302)
						)
						(arc
							(start -0.4318 0.3302)
							(mid -0.402042 0.402042)
							(end -0.3302 0.4318)
						)
						(arc
							(start 0.3302 0.4318)
							(mid 0.402042 0.402042)
							(end 0.4318 0.3302)
						)
						(arc
							(start 0.4318 -0.3302)
							(mid 0.402042 -0.402042)
							(end 0.3302 -0.4318)
						)
					)
					(width 0)
					(fill yes)
				)
			)
		)
		(pad "2" smd custom
			(at 0 0.762 180)
			(size 0.2159 0.2159)
			(layers "F.Cu" "F.Mask" "F.Paste")
			(net "DRIVE_B_32_INS")
			(options
				(clearance outline)
				(anchor circle)
			)
			(primitives
				(gr_poly
					(pts
						(arc
							(start -0.3302 -0.4318)
							(mid -0.402042 -0.402042)
							(end -0.4318 -0.3302)
						)
						(arc
							(start -0.4318 0.3302)
							(mid -0.402042 0.402042)
							(end -0.3302 0.4318)
						)
						(arc
							(start 0.3302 0.4318)
							(mid 0.402042 0.402042)
							(end 0.4318 0.3302)
						)
						(arc
							(start 0.4318 -0.3302)
							(mid 0.402042 -0.402042)
							(end 0.3302 -0.4318)
						)
					)
					(width 0)
					(fill yes)
				)
			)
		)
	)
	(footprint ""
		(layer "F.Cu")
		(at 320.312796 -375.0056 -90)
		(property "Reference" "Q217"
			(at 0 0 270)
			(layer "F.SilkS")
			(hide yes)
			(effects
				(font
					(size 1.27 1.27)
				)
			)
		)
		(property "Value" "2N7002KDW-GP"
			(at -2.3622 -8.2042 270)
			(unlocked yes)
			(layer "F.Fab")
			(hide yes)
			(effects
				(font
					(size 1.016 1.016)
					(thickness 0.1524)
				)
			)
		)
		(property "Device Type" "SOT-363H44"
			(at -2.3622 -10.1092 270)
			(unlocked yes)
			(layer "F.Fab")
			(hide yes)
			(effects
				(font
					(size 1.016 1.016)
					(thickness 0.1524)
				)
			)
		)
		(duplicate_pad_numbers_are_jumpers no)
		(fp_line
			(start -1.4478 1.7018)
			(end 1.4478 1.7018)
			(stroke
				(width 0.1524)
				(type default)
			)
			(layer "F.SilkS")
		)
		(fp_line
			(start 1.4478 1.7018)
			(end 1.4478 -1.7018)
			(stroke
				(width 0.1524)
				(type default)
			)
			(layer "F.SilkS")
		)
		(fp_line
			(start -1.27 1.524)
			(end -1.27 0.6604)
			(stroke
				(width 0.4826)
				(type default)
			)
			(layer "F.SilkS")
		)
		(fp_line
			(start -1.4478 -1.7018)
			(end -1.4478 1.7018)
			(stroke
				(width 0.1524)
				(type default)
			)
			(layer "F.SilkS")
		)
		(fp_line
			(start 1.4478 -1.7018)
			(end -1.4478 -1.7018)
			(stroke
				(width 0.1524)
				(type default)
			)
			(layer "F.SilkS")
		)
		(fp_poly
			(pts
				(xy -1.524 -1.778) (xy 1.524 -1.778) (xy 1.524 1.778) (xy -1.524 1.778)
			)
			(stroke
				(width 0)
				(type default)
			)
			(fill no)
			(layer "F.CrtYd")
		)
		(fp_poly
			(pts
				(xy -1.524 -1.778) (xy 1.524 -1.778) (xy 1.524 1.778) (xy -1.524 1.778)
			)
			(stroke
				(width 0)
				(type default)
			)
			(fill no)
			(layer "F.Fab")
		)
		(pad "1" smd rect
			(at -0.65024 0.9398 270)
			(size 0.4064 1.016)
			(layers "F.Cu" "F.Mask" "F.Paste")
			(net "GND")
		)
		(pad "2" smd rect
			(at 0 0.9398 270)
			(size 0.4064 1.016)
			(layers "F.Cu" "F.Mask" "F.Paste")
			(net "FAN_LED2_D")
		)
		(pad "3" smd rect
			(at 0.65024 0.9398 270)
			(size 0.4064 1.016)
			(layers "F.Cu" "F.Mask" "F.Paste")
			(net "FAN_LED2_D")
		)
		(pad "4" smd rect
			(at 0.65024 -0.9398 270)
			(size 0.4064 1.016)
			(layers "F.Cu" "F.Mask" "F.Paste")
			(net "GND")
		)
		(pad "5" smd rect
			(at 0 -0.9398 270)
			(size 0.4064 1.016)
			(layers "F.Cu" "F.Mask" "F.Paste")
			(net "FAN_LED2")
		)
		(pad "6" smd rect
			(at -0.65024 -0.9398 270)
			(size 0.4064 1.016)
			(layers "F.Cu" "F.Mask" "F.Paste")
			(net "FAN_LED2_D2")
		)
	)
	(footprint ""
		(layer "F.Cu")
		(at 117.602 -134.493 90)
		(property "Reference" "R427"
			(at 0 0 90)
			(layer "F.SilkS")
			(hide yes)
			(effects
				(font
					(size 1.27 1.27)
				)
			)
		)
		(property "Value" "4K7R2F-GP"
			(at 0.064008 -3.993896 90)
			(unlocked yes)
			(layer "F.Fab")
			(hide yes)
			(effects
				(font
					(size 1.016 1.016)
					(thickness 0.1524)
				)
			)
		)
		(property "Device Type" "R402H16"
			(at 0.064008 -5.517896 90)
			(unlocked yes)
			(layer "F.Fab")
			(hide yes)
			(effects
				(font
					(size 1.016 1.016)
					(thickness 0.1524)
				)
			)
		)
		(duplicate_pad_numbers_are_jumpers no)
		(fp_line
			(start 0.508 -0.9398)
			(end -0.508 -0.9398)
			(stroke
				(width 0.1524)
				(type default)
			)
			(layer "F.SilkS")
		)
		(fp_line
			(start -0.508 -0.9398)
			(end -0.508 0.9398)
			(stroke
				(width 0.1524)
				(type default)
			)
			(layer "F.SilkS")
		)
		(fp_rect
			(start -0.508 0.9398)
			(end 0.508 -0.9398)
			(stroke
				(width 0)
				(type default)
			)
			(fill no)
			(layer "F.CrtYd")
		)
		(fp_rect
			(start -0.508 0.9398)
			(end 0.508 -0.9398)
			(stroke
				(width 0)
				(type default)
			)
			(fill no)
			(layer "F.Fab")
		)
		(pad "1" smd custom
			(at 0 -0.4445 90)
			(size 0.1397 0.1397)
			(layers "F.Cu" "F.Mask" "F.Paste")
			(net "SW_PWR_R_HDD15")
			(options
				(clearance outline)
				(anchor circle)
			)
			(primitives
				(gr_poly
					(pts
						(arc
							(start -0.1778 -0.2794)
							(mid -0.249642 -0.249642)
							(end -0.2794 -0.1778)
						)
						(arc
							(start -0.2794 0.1778)
							(mid -0.249642 0.249642)
							(end -0.1778 0.2794)
						)
						(arc
							(start 0.1778 0.2794)
							(mid 0.249642 0.249642)
							(end 0.2794 0.1778)
						)
						(arc
							(start 0.2794 -0.1778)
							(mid 0.249642 -0.249642)
							(end 0.1778 -0.2794)
						)
					)
					(width 0)
					(fill yes)
				)
			)
		)
		(pad "2" smd custom
			(at 0 0.4445 90)
			(size 0.1397 0.1397)
			(layers "F.Cu" "F.Mask" "F.Paste")
			(net "GND")
			(options
				(clearance outline)
				(anchor circle)
			)
			(primitives
				(gr_poly
					(pts
						(arc
							(start -0.1778 -0.2794)
							(mid -0.249642 -0.249642)
							(end -0.2794 -0.1778)
						)
						(arc
							(start -0.2794 0.1778)
							(mid -0.249642 0.249642)
							(end -0.1778 0.2794)
						)
						(arc
							(start 0.1778 0.2794)
							(mid 0.249642 0.249642)
							(end 0.2794 0.1778)
						)
						(arc
							(start 0.2794 -0.1778)
							(mid 0.249642 -0.249642)
							(end 0.1778 -0.2794)
						)
					)
					(width 0)
					(fill yes)
				)
			)
		)
	)
	(footprint ""
		(layer "F.Cu")
		(at 212.6488 -203.327 90)
		(property "Reference" "C9"
			(at 0 0 90)
			(layer "F.SilkS")
			(hide yes)
			(effects
				(font
					(size 1.27 1.27)
				)
			)
		)
		(property "Value" "SC1U16V3KX-5GP"
			(at 0 -2.8194 90)
			(unlocked yes)
			(layer "F.Fab")
			(hide yes)
			(effects
				(font
					(size 1.016 1.016)
					(thickness 0.1524)
				)
			)
		)
		(property "Device Type" "C603H36"
			(at 0 -4.3434 90)
			(unlocked yes)
			(layer "F.Fab")
			(hide yes)
			(effects
				(font
					(size 1.016 1.016)
					(thickness 0.1524)
				)
			)
		)
		(duplicate_pad_numbers_are_jumpers no)
		(fp_line
			(start 0.508 0)
			(end -0.508 0)
			(stroke
				(width 0.2032)
				(type default)
			)
			(layer "F.SilkS")
		)
		(fp_rect
			(start -0.5842 1.3335)
			(end 0.5842 -1.3335)
			(stroke
				(width 0)
				(type default)
			)
			(fill no)
			(layer "F.CrtYd")
		)
		(fp_rect
			(start -0.5842 1.3335)
			(end 0.5842 -1.3335)
			(stroke
				(width 0)
				(type default)
			)
			(fill no)
			(layer "F.Fab")
		)
		(pad "1" smd custom
			(at 0 -0.762 90)
			(size 0.2159 0.2159)
			(layers "F.Cu" "F.Mask" "F.Paste")
			(net "P3V3_STBY_B")
			(options
				(clearance outline)
				(anchor circle)
			)
			(primitives
				(gr_poly
					(pts
						(arc
							(start -0.3302 -0.4318)
							(mid -0.402042 -0.402042)
							(end -0.4318 -0.3302)
						)
						(arc
							(start -0.4318 0.3302)
							(mid -0.402042 0.402042)
							(end -0.3302 0.4318)
						)
						(arc
							(start 0.3302 0.4318)
							(mid 0.402042 0.402042)
							(end 0.4318 0.3302)
						)
						(arc
							(start 0.4318 -0.3302)
							(mid 0.402042 -0.402042)
							(end 0.3302 -0.4318)
						)
					)
					(width 0)
					(fill yes)
				)
			)
		)
		(pad "2" smd custom
			(at 0 0.762 90)
			(size 0.2159 0.2159)
			(layers "F.Cu" "F.Mask" "F.Paste")
			(net "GND")
			(options
				(clearance outline)
				(anchor circle)
			)
			(primitives
				(gr_poly
					(pts
						(arc
							(start -0.3302 -0.4318)
							(mid -0.402042 -0.402042)
							(end -0.4318 -0.3302)
						)
						(arc
							(start -0.4318 0.3302)
							(mid -0.402042 0.402042)
							(end -0.3302 0.4318)
						)
						(arc
							(start 0.3302 0.4318)
							(mid 0.402042 0.402042)
							(end 0.4318 0.3302)
						)
						(arc
							(start 0.4318 -0.3302)
							(mid 0.402042 -0.402042)
							(end 0.3302 -0.4318)
						)
					)
					(width 0)
					(fill yes)
				)
			)
		)
	)
	(footprint ""
		(layer "F.Cu")
		(at 284.8864 -307.6956)
		(property "Reference" "TC5"
			(at 0 0 0)
			(layer "F.SilkS")
			(hide yes)
			(effects
				(font
					(size 1.27 1.27)
				)
			)
		)
		(property "Value" "SE270U16VM-8-GP"
			(at -4.5974 -2.54 0)
			(unlocked yes)
			(layer "F.Fab")
			(hide yes)
			(effects
				(font
					(size 1.016 1.016)
					(thickness 0.1524)
				)
			)
		)
		(property "Device Type" "SE361416H394"
			(at -4.5974 -4.064 0)
			(unlocked yes)
			(layer "F.Fab")
			(hide yes)
			(effects
				(font
					(size 1.016 1.016)
					(thickness 0.1524)
				)
			)
		)
		(duplicate_pad_numbers_are_jumpers no)
		(fp_line
			(start -3.556 -3.4163)
			(end -2.3622 -4.6101)
			(stroke
				(width 0.1524)
				(type default)
			)
			(layer "F.SilkS")
		)
		(fp_line
			(start -3.556 4.6101)
			(end -3.556 -3.4163)
			(stroke
				(width 0.1524)
				(type default)
			)
			(layer "F.SilkS")
		)
		(fp_line
			(start -2.3622 -4.6101)
			(end 2.3622 -4.6101)
			(stroke
				(width 0.1524)
				(type default)
			)
			(layer "F.SilkS")
		)
		(fp_line
			(start 2.3622 -4.6101)
			(end 3.556 -3.4163)
			(stroke
				(width 0.1524)
				(type default)
			)
			(layer "F.SilkS")
		)
		(fp_line
			(start 3.556 -3.4163)
			(end 3.556 4.6101)
			(stroke
				(width 0.1524)
				(type default)
			)
			(layer "F.SilkS")
		)
		(fp_line
			(start 3.556 4.6101)
			(end -3.556 4.6101)
			(stroke
				(width 0.1524)
				(type default)
			)
			(layer "F.SilkS")
		)
		(fp_rect
			(start -3.302 3.6449)
			(end 3.302 -3.6449)
			(stroke
				(width 0)
				(type default)
			)
			(fill no)
			(layer "F.CrtYd")
		)
		(fp_poly
			(pts
				(xy 3.81 4.6863) (xy 3.81 -3.4925) (xy 3.302 -3.4925) (xy 3.302 3.6449) (xy -3.302 3.6449) (xy -3.302 -3.6449)
				(xy 3.302 -3.6449) (xy 3.302 -3.5052) (xy 3.81 -3.5052) (xy 3.81 -4.6863) (xy -3.81 -4.6863) (xy -3.81 4.6863)
			)
			(stroke
				(width 0)
				(type default)
			)
			(fill no)
			(layer "F.CrtYd")
		)
		(fp_rect
			(start -3.81 4.6863)
			(end 3.81 -4.6863)
			(stroke
				(width 0)
				(type default)
			)
			(fill no)
			(layer "F.Fab")
		)
		(pad "1" smd rect
			(at 0 -2.574036)
			(size 1.4224 3.556)
			(layers "F.Cu" "F.Mask" "F.Paste")
			(net "P12V_B")
		)
		(pad "2" smd rect
			(at 0 2.574036)
			(size 1.4224 3.556)
			(layers "F.Cu" "F.Mask" "F.Paste")
			(net "GND")
		)
	)
	(footprint ""
		(layer "F.Cu")
		(at 252.080522 -358.622346)
		(property "Reference" "C560"
			(at 0 0 0)
			(layer "F.SilkS")
			(hide yes)
			(effects
				(font
					(size 1.27 1.27)
				)
			)
		)
		(property "Value" "SCD1U25V2KX-2-GP"
			(at 1.1811 -2.7051 0)
			(unlocked yes)
			(layer "F.Fab")
			(hide yes)
			(effects
				(font
					(size 1.016 1.016)
					(thickness 0.1524)
				)
			)
		)
		(property "Device Type" "C402H22"
			(at 1.1811 -4.2291 0)
			(unlocked yes)
			(layer "F.Fab")
			(hide yes)
			(effects
				(font
					(size 1.016 1.016)
					(thickness 0.1524)
				)
			)
		)
		(duplicate_pad_numbers_are_jumpers no)
		(fp_rect
			(start -0.4318 0.9525)
			(end 0.4318 -0.9525)
			(stroke
				(width 0)
				(type default)
			)
			(fill no)
			(layer "F.CrtYd")
		)
		(fp_rect
			(start -0.4318 0.9525)
			(end 0.4318 -0.9525)
			(stroke
				(width 0)
				(type default)
			)
			(fill no)
			(layer "F.Fab")
		)
		(pad "1" smd custom
			(at 0 -0.4445)
			(size 0.1524 0.1524)
			(layers "F.Cu" "F.Mask" "F.Paste")
			(net "MB3_ISET_R")
			(options
				(clearance outline)
				(anchor circle)
			)
			(primitives
				(gr_poly
					(pts
						(arc
							(start 0.3048 -0.2032)
							(mid 0.275042 -0.275042)
							(end 0.2032 -0.3048)
						)
						(arc
							(start -0.2032 -0.3048)
							(mid -0.275042 -0.275042)
							(end -0.3048 -0.2032)
						)
						(arc
							(start -0.3048 0.2032)
							(mid -0.275042 0.275042)
							(end -0.2032 0.3048)
						)
						(arc
							(start 0.2032 0.3048)
							(mid 0.275042 0.275042)
							(end 0.3048 0.2032)
						)
					)
					(width 0)
					(fill yes)
				)
			)
		)
		(pad "2" smd custom
			(at 0 0.4445)
			(size 0.1524 0.1524)
			(layers "F.Cu" "F.Mask" "F.Paste")
			(net "AGND_CURRENT_DPB")
			(options
				(clearance outline)
				(anchor circle)
			)
			(primitives
				(gr_poly
					(pts
						(arc
							(start 0.3048 -0.2032)
							(mid 0.275042 -0.275042)
							(end 0.2032 -0.3048)
						)
						(arc
							(start -0.2032 -0.3048)
							(mid -0.275042 -0.275042)
							(end -0.3048 -0.2032)
						)
						(arc
							(start -0.3048 0.2032)
							(mid -0.275042 0.275042)
							(end -0.2032 0.3048)
						)
						(arc
							(start 0.2032 0.3048)
							(mid 0.275042 0.275042)
							(end 0.3048 0.2032)
						)
					)
					(width 0)
					(fill yes)
				)
			)
		)
	)
	(footprint ""
		(layer "F.Cu")
		(at 377.698 -214.249)
		(property "Reference" "R332"
			(at 0 0 0)
			(layer "F.SilkS")
			(hide yes)
			(effects
				(font
					(size 1.27 1.27)
				)
			)
		)
		(property "Value" "130R3F-GP"
			(at -0.0254 -2.5146 0)
			(unlocked yes)
			(layer "F.Fab")
			(hide yes)
			(effects
				(font
					(size 1.016 1.016)
					(thickness 0.1524)
				)
			)
		)
		(property "Device Type" "R603H22"
			(at -0.0254 -4.0386 0)
			(unlocked yes)
			(layer "F.Fab")
			(hide yes)
			(effects
				(font
					(size 1.016 1.016)
					(thickness 0.1524)
				)
			)
		)
		(duplicate_pad_numbers_are_jumpers no)
		(fp_line
			(start -0.4826 0)
			(end -0.2032 0)
			(stroke
				(width 0.2032)
				(type default)
			)
			(layer "F.SilkS")
		)
		(fp_line
			(start 0.2032 0)
			(end 0.4826 0)
			(stroke
				(width 0.2032)
				(type default)
			)
			(layer "F.SilkS")
		)
		(fp_rect
			(start -0.5842 1.3335)
			(end 0.5842 -1.3335)
			(stroke
				(width 0)
				(type default)
			)
			(fill no)
			(layer "F.CrtYd")
		)
		(fp_rect
			(start -0.5842 1.3335)
			(end 0.5842 -1.3335)
			(stroke
				(width 0)
				(type default)
			)
			(fill no)
			(layer "F.Fab")
		)
		(pad "1" smd custom
			(at 0 -0.762)
			(size 0.2159 0.2159)
			(layers "F.Cu" "F.Mask" "F.Paste")
			(net "P5V_B_3")
			(options
				(clearance outline)
				(anchor circle)
			)
			(primitives
				(gr_poly
					(pts
						(arc
							(start -0.3302 -0.4318)
							(mid -0.402042 -0.402042)
							(end -0.4318 -0.3302)
						)
						(arc
							(start -0.4318 0.3302)
							(mid -0.402042 0.402042)
							(end -0.3302 0.4318)
						)
						(arc
							(start 0.3302 0.4318)
							(mid 0.402042 0.402042)
							(end 0.4318 0.3302)
						)
						(arc
							(start 0.4318 -0.3302)
							(mid 0.402042 -0.402042)
							(end 0.3302 -0.4318)
						)
					)
					(width 0)
					(fill yes)
				)
			)
		)
		(pad "2" smd custom
			(at 0 0.762)
			(size 0.2159 0.2159)
			(layers "F.Cu" "F.Mask" "F.Paste")
			(net "FLT_HDD8")
			(options
				(clearance outline)
				(anchor circle)
			)
			(primitives
				(gr_poly
					(pts
						(arc
							(start -0.3302 -0.4318)
							(mid -0.402042 -0.402042)
							(end -0.4318 -0.3302)
						)
						(arc
							(start -0.4318 0.3302)
							(mid -0.402042 0.402042)
							(end -0.3302 0.4318)
						)
						(arc
							(start 0.3302 0.4318)
							(mid 0.402042 0.402042)
							(end 0.4318 0.3302)
						)
						(arc
							(start 0.4318 -0.3302)
							(mid 0.402042 -0.402042)
							(end 0.3302 -0.4318)
						)
					)
					(width 0)
					(fill yes)
				)
			)
		)
	)
)
